# BASEBOARD_FAB2 (Tioga Pass) — schematic netlist excerpt (pin names and nets, part order shuffled) for the footprints in the layout excerpt that follows; sources: Cadence DE-HDL packaged netlist, KiCad conversion of Wiwynn_Tioga_Pass_MB.brd

C9F10  CAP  1000PF 50V 10% X7R  pkg 0402LF  page 239 : A = PWRGD_P1V2_BMC_STBY_R ; B = GND
T1P28  TPAD-SE-2P-GP  pkg DISCRET-GA1  page 256 : \1\ = L10_40OHM_6INCH ; GND1 = GND
R7F22  RES  1.00K 1% CHIP  pkg 0402  page 215 : A = P3V3_STBY ; B = PWRGD_PVDDQ_ABC_R

(kicad_pcb
	(version 20260206)
	(generator "pcbnew")
	(generator_version "10.0")
	(general
		(thickness 1.6)
		(legacy_teardrops no)
	)
	(paper "A4")
	(title_block
		(title "Wiwynn_Tioga_Pass_MB.brd")
		(comment 1 "Tioga Pass / footprints 1436-1438 of 4770")
	)
	(layers
		(0 "F.Cu" signal "TOP")
		(4 "In1.Cu" signal "L2GND")
		(6 "In2.Cu" signal "L3")
		(8 "In3.Cu" signal "L4GND")
		(10 "In4.Cu" signal "L5")
		(12 "In5.Cu" signal "L6GND")
		(14 "In6.Cu" signal "L7VCC")
		(16 "In7.Cu" signal "L8VCC")
		(18 "In8.Cu" signal "L9GND")
		(20 "In9.Cu" signal "L10")
		(22 "In10.Cu" signal "L11GND")
		(24 "In11.Cu" signal "L12")
		(26 "In12.Cu" signal "L13GND")
		(2 "B.Cu" signal "BOTTOM")
		(9 "F.Adhes" user "F.Adhesive")
		(11 "B.Adhes" user "B.Adhesive")
		(13 "F.Paste" user "Package Geometry/Pastemask Top")
		(15 "B.Paste" user "Package Geometry/Pastemask Bottom")
		(5 "F.SilkS" user "Ref Des/Silkscreen Top")
		(7 "B.SilkS" user "Ref Des/Silkscreen Bottom")
		(1 "F.Mask" user "Board Geometry/Soldermask Top")
		(3 "B.Mask" user "Board Geometry/Soldermask Bottom")
		(17 "Dwgs.User" user "User.Drawings")
		(19 "Cmts.User" user "User.Comments")
		(21 "Eco1.User" user "User.Eco1")
		(23 "Eco2.User" user "User.Eco2")
		(25 "Edge.Cuts" user "Board Geometry/Outline")
		(27 "Margin" user)
		(31 "F.CrtYd" user "Package Geometry/Place Bound Top")
		(29 "B.CrtYd" user "Package Geometry/Place Bound Bottom")
		(35 "F.Fab" user "Ref Des/Assembly Top")
		(33 "B.Fab" user "Ref Des/Assembly Bottom")
	)
	(footprint ""
		(layer "F.Cu")
		(at 473.075 -38.1 180)
		(property "Reference" "C9F10"
			(at 0 0 180)
			(layer "F.SilkS")
			(hide yes)
			(effects
				(font
					(size 1.27 1.27)
				)
			)
		)
		(property "Value" ""
			(at 0 0 180)
			(layer "F.Fab")
			(effects
				(font
					(size 1.27 1.27)
				)
			)
		)
		(duplicate_pad_numbers_are_jumpers no)
		(fp_poly
			(pts
				(xy 0.3048 -0.1016) (xy 0.3048 0.9906) (xy -0.3048 0.9906) (xy -0.3048 -0.1016)
			)
			(stroke
				(width 0)
				(type default)
			)
			(fill no)
			(layer "F.CrtYd")
		)
		(fp_line
			(start 0.3048 0.9906)
			(end 0.3048 -0.1016)
			(stroke
				(width 0.1)
				(type default)
			)
			(layer "F.Fab")
		)
		(fp_line
			(start 0.3048 -0.1016)
			(end -0.3048 -0.1016)
			(stroke
				(width 0.1)
				(type default)
			)
			(layer "F.Fab")
		)
		(fp_line
			(start -0.3048 0.9906)
			(end 0.3048 0.9906)
			(stroke
				(width 0.1)
				(type default)
			)
			(layer "F.Fab")
		)
		(fp_line
			(start -0.3048 -0.1016)
			(end -0.3048 0.9906)
			(stroke
				(width 0.1)
				(type default)
			)
			(layer "F.Fab")
		)
		(pad "1" smd rect
			(at 0 0 180)
			(size 0.508 0.508)
			(layers "F.Cu" "F.Mask" "F.Paste")
			(net "PWRGD_P1V2_BMC_STBY_R")
		)
		(pad "2" smd rect
			(at 0 0.889 180)
			(size 0.508 0.508)
			(layers "F.Cu" "F.Mask" "F.Paste")
			(net "GND")
		)
		(zone
			(layer "F.Cu")
			(hatch none 0.5)
			(connect_pads
				(clearance 0)
			)
			(min_thickness 0.25)
			(keepout
				(tracks not_allowed)
				(vias allowed)
				(pads allowed)
				(copperpour not_allowed)
				(footprints allowed)
			)
			(placement
				(enabled no)
				(sheetname "")
			)
			(fill
				(thermal_gap 0.5)
				(thermal_bridge_width 0.5)
				(island_removal_mode 0)
			)
			(polygon
				(pts
					(xy 473.329 -38.735) (xy 472.821 -38.735) (xy 472.821 -38.354) (xy 473.329 -38.354)
				)
			)
		)
		(zone
			(layer "F.Cu")
			(hatch none 0.5)
			(connect_pads
				(clearance 0)
			)
			(min_thickness 0.25)
			(keepout
				(tracks allowed)
				(vias not_allowed)
				(pads allowed)
				(copperpour not_allowed)
				(footprints allowed)
			)
			(placement
				(enabled no)
				(sheetname "")
			)
			(fill
				(thermal_gap 0.5)
				(thermal_bridge_width 0.5)
				(island_removal_mode 0)
			)
			(polygon
				(pts
					(xy 473.329 -38.354) (xy 472.821 -38.354) (xy 472.821 -38.735) (xy 473.329 -38.735)
				)
			)
		)
	)
	(footprint ""
		(layer "F.Cu")
		(at 343.281 -20.447)
		(property "Reference" "R7F22"
			(at 0 0 0)
			(layer "F.SilkS")
			(hide yes)
			(effects
				(font
					(size 1.27 1.27)
				)
			)
		)
		(property "Value" ""
			(at 0 0 0)
			(layer "F.Fab")
			(effects
				(font
					(size 1.27 1.27)
				)
			)
		)
		(duplicate_pad_numbers_are_jumpers no)
		(fp_rect
			(start -0.2794 0.9906)
			(end 0.2794 -0.1016)
			(stroke
				(width 0)
				(type default)
			)
			(fill no)
			(layer "F.CrtYd")
		)
		(fp_line
			(start -0.2794 -0.1016)
			(end -0.2794 0.9906)
			(stroke
				(width 0.1)
				(type default)
			)
			(layer "F.Fab")
		)
		(fp_line
			(start -0.2794 0.9906)
			(end 0.2794 0.9906)
			(stroke
				(width 0.1)
				(type default)
			)
			(layer "F.Fab")
		)
		(fp_line
			(start 0.2794 -0.1016)
			(end -0.2794 -0.1016)
			(stroke
				(width 0.1)
				(type default)
			)
			(layer "F.Fab")
		)
		(fp_line
			(start 0.2794 0.9906)
			(end 0.2794 -0.1016)
			(stroke
				(width 0.1)
				(type default)
			)
			(layer "F.Fab")
		)
		(pad "1" smd rect
			(at 0 0)
			(size 0.508 0.508)
			(layers "F.Cu" "F.Mask" "F.Paste")
			(net "P3V3_STBY")
		)
		(pad "2" smd rect
			(at 0 0.889)
			(size 0.508 0.508)
			(layers "F.Cu" "F.Mask" "F.Paste")
			(net "PWRGD_PVDDQ_ABC_R")
		)
		(zone
			(layer "F.Cu")
			(hatch none 0.5)
			(connect_pads
				(clearance 0)
			)
			(min_thickness 0.25)
			(keepout
				(tracks not_allowed)
				(vias allowed)
				(pads allowed)
				(copperpour not_allowed)
				(footprints allowed)
			)
			(placement
				(enabled no)
				(sheetname "")
			)
			(fill
				(thermal_gap 0.5)
				(thermal_bridge_width 0.5)
				(island_removal_mode 0)
			)
			(polygon
				(pts
					(xy 343.027 -19.812) (xy 343.535 -19.812) (xy 343.535 -20.193) (xy 343.027 -20.193)
				)
			)
		)
		(zone
			(layer "F.Cu")
			(hatch none 0.5)
			(connect_pads
				(clearance 0)
			)
			(min_thickness 0.25)
			(keepout
				(tracks allowed)
				(vias not_allowed)
				(pads allowed)
				(copperpour not_allowed)
				(footprints allowed)
			)
			(placement
				(enabled no)
				(sheetname "")
			)
			(fill
				(thermal_gap 0.5)
				(thermal_bridge_width 0.5)
				(island_removal_mode 0)
			)
			(polygon
				(pts
					(xy 343.027 -19.812) (xy 343.535 -19.812) (xy 343.535 -20.193) (xy 343.027 -20.193)
				)
			)
		)
	)
	(footprint ""
		(layer "F.Cu")
		(at 24.257 10.7315 -90)
		(property "Reference" "T1P28"
			(at 0 0 270)
			(layer "F.SilkS")
			(hide yes)
			(effects
				(font
					(size 1.27 1.27)
				)
			)
		)
		(property "Value" "*"
			(at 0 -3.44805 270)
			(unlocked yes)
			(layer "F.Fab")
			(hide yes)
			(effects
				(font
					(size 0.889 0.889)
					(thickness 0.1524)
				)
			)
		)
		(property "Device Type" "TPAD-SE-2P-GP_DISCRET-GA1-TPADA"
			(at 0 -4.97205 270)
			(unlocked yes)
			(layer "F.Fab")
			(hide yes)
			(effects
				(font
					(size 0.889 0.889)
					(thickness 0.1524)
				)
			)
		)
		(duplicate_pad_numbers_are_jumpers no)
		(fp_line
			(start -1.016 2.286)
			(end -1.016 -2.286)
			(stroke
				(width 0.1524)
				(type default)
			)
			(layer "F.SilkS")
		)
		(fp_line
			(start 1.016 2.286)
			(end -1.016 2.286)
			(stroke
				(width 0.1524)
				(type default)
			)
			(layer "F.SilkS")
		)
		(fp_line
			(start -1.016 -2.286)
			(end 1.016 -2.286)
			(stroke
				(width 0.1524)
				(type default)
			)
			(layer "F.SilkS")
		)
		(fp_line
			(start 1.016 -2.286)
			(end 1.016 2.286)
			(stroke
				(width 0.1524)
				(type default)
			)
			(layer "F.SilkS")
		)
		(fp_rect
			(start -1.27 2.54)
			(end 1.27 -2.54)
			(stroke
				(width 0)
				(type default)
			)
			(fill no)
			(layer "F.CrtYd")
		)
		(fp_rect
			(start -1.27 2.54)
			(end 1.27 -2.54)
			(stroke
				(width 0)
				(type default)
			)
			(fill no)
			(layer "F.Fab")
		)
		(pad "1" thru_hole circle
			(at 0 -1.27 270)
			(size 1.524 1.524)
			(drill 0.9144)
			(layers "*.Cu" "*.Mask")
			(remove_unused_layers no)
			(net "L10_40OHM_6INCH")
			(clearance -0.0508)
			(thermal_gap 0.127)
			(padstack
				(mode front_inner_back)
				(layer "Inner"
					(shape circle)
					(size 1.1684 1.1684)
					(clearance 0.127)
				)
				(layer "B.Cu"
					(shape circle)
					(size 1.524 1.524)
					(clearance -0.0508)
				)
			)
		)
		(pad "GND1" thru_hole rect
			(at 0 1.27 270)
			(size 1.524 1.524)
			(drill 0.9144)
			(layers "*.Cu" "*.Mask")
			(remove_unused_layers no)
			(net "GND")
			(clearance -0.0508)
			(thermal_gap 0.127)
			(padstack
				(mode front_inner_back)
				(layer "Inner"
					(shape circle)
					(size 1.1684 1.1684)
					(clearance 0.127)
				)
				(layer "B.Cu"
					(shape rect)
					(size 1.524 1.524)
					(clearance -0.0508)
				)
			)
		)
	)
)
